FILE_TYPE = CONNECTIVITY;
{Allegro Design Entry HDL 16.6-p007 (v16-6-112F) 10/10/2012}
"PAGE_NUMBER" = 177;
0"NC";
1"P3V3\g";
2"GND\g";
3"P5V_STBY\g";
4"P3V3\g";
5"GND\g";
6"GND\g";
7"P3V3_STBY\g";
8"P3V3_STBY\g";
9"P3V3_STBY\g";
10"GND\g";
11"P3V3\g";
12"FM_BMC_FAULT_LED";
13"LED_SATA_ACT_R_N";
14"LED_SAS_ACT_R_N";
15"FP_LED_HDD_ACTIVITY_AND_N";
16"FP_LED_HDD_ACTIVITY_AND_R_N";
17"FM_BMC_FAULT_LED_N";
18"LED_PCH_SSATA_HDD_N";
19"LED_PCH_SATA_HDD_N";
20"FM_RED_LED_CATHODE";
21"FM_RED_LED_ANODE";
22"LED_P5V_STBY";
%"P3V3"
"1","(-6975,6775)","0","mstr_symbols","I10";
;
VOLTAGE"+3.3"
SIZE"1B"
CDS_LIB"mstr_symbols"
ROOM"SB"
BODY_TYPE"PLUMBING"
HDL_POWER"P3V3";
"G\NAC"1;
%"CAP_A"
"1","(-5625,5425)","0","dev_discrete","I20";
;
LOCATION"C1M3"
PART_NUMBER"D97712-004"
VALUE"1.0UF"
TOLERANCE"10%"
PACK_TYPE"0402V"
VOLTAGE"6.3V"
MATERIAL"X6S"
CDS_LOCATION"C1M3"
CDS_LIB"dev_discrete"
CDS_SEC"1"
$SEC"1"
ROOM"MIO_CHASSIS";
"B"
$PN"2"5;
"A"
$PN"1"4;
%"RES"
"1","(-7900,6225)","0","mstr_discrete","I3";
;
MATERIAL"CHIP"
LOCATION"R1M13"
PART_NUMBER"G21497-005"
PACK_TYPE"0402"
WATTAGE"1/16W"
TOLERANCE"5%"
VALUE"0.0"
CDS_LIB"mstr_discrete"
CDS_SEC"1"
$SEC"1"
CDS_LOCATION"R1M13"
ROOM"MIO_CHASSIS";
"B"
$PN"2"14;
"A"
$PN"1"18;
%"GND"
"1","(-3825,8250)","0","mstr_symbols","I30";
;
VOLTAGE"0"
CDS_LIB"mstr_symbols"
SIZE"1B"
ROOM"DEBUG"
BODY_TYPE"PLUMBING"
HDL_POWER"GND";
"A\NAC"2;
%"LED"
"2","(-3825,8475)","0","mstr_discrete","I31";
;
CDS_SEC"1"
LOCATION"DS9A6"
PART_NUMBER"C97278-010"
MATERIAL"IC"
COLOR"GREEN"
PACK_TYPE"A1LF"
SEC_TYPE"A1LF"
CDS_LIB"mstr_discrete"
SEC"1"
CDS_LOCATION"DS9A6"
ROOM"MIO_CHASSIS";
"C"
$PN"2"2;
"A"
$PN"1"22;
%"RES"
"2","(-3825,8850)","0","mstr_discrete","I33";
;
LOCATION"R1L37"
VALUE"301.0"
TOLERANCE"1%"
PACK_TYPE"0402"
MATERIAL"CHIP"
WATTAGE"1/16W"
PART_NUMBER"G21796-076"
CDS_LIB"mstr_discrete"
SIGNAL_MODEL"DEFAULT_RESISTOR_332OHM_2_1"
CDS_SEC"1"
$SEC"1"
CDS_LOCATION"R1L37"
ROOM"MIO_CHASSIS";
"A"
$PN"1"3;
"B"
$PN"2"22;
%"P5V_STBY"
"1","(-3825,9050)","0","mstr_symbols","I36";
;
VOLTAGE"5.0V"
CDS_LIB"mstr_symbols"
SIZE"1B"
BODY_TYPE"PLUMBING"
HDL_POWER"P5V_STBY";
"G\NAC"3;
%"LED"
"3","(-5550,6275)","0","mstr_discrete","I42";
;
CDS_SEC"1"
COLOR"GREEN"
MATERIAL"IC"
LOCATION"DS9A2"
PART_NUMBER"C96565-011"
NEW_PN"83.00320.A70"
CDS_LOCATION"DS9A2"
CDS_LIB"mstr_discrete"
SEC"1"
SEC_TYPE"1NCLF"
ROOM"MIO_CHASSIS"
PACK_TYPE"1NCLF";
"A"
$PN"2"16;
"C"
$PN"1"15;
%"RES"
"2","(-4675,6600)","0","mstr_discrete","I43";
;
CDS_SEC"1"
PART_NUMBER"G21796-298"
PACK_TYPE"0402"
MATERIAL"CHIP"
TOLERANCE"1.0%"
VALUE"64.9"
WATTAGE"1/16W"
LOCATION"R1L21"
CONFIG"64.12005.6DL"
CDS_LIB"mstr_discrete"
SEC_TYPE"0402"
SEC"1"
CDS_LOCATION"R1L21"
ROOM"MIO_CHASSIS";
"A"
$PN"1"11;
"B"
$PN"2"16;
%"P3V3"
"1","(-5625,5725)","0","mstr_symbols","I45";
;
VOLTAGE"+3.3"
CDS_LIB"mstr_symbols"
SIZE"1B"
ROOM"SM_CONTROLLER"
BODY_TYPE"PLUMBING"
HDL_POWER"P3V3";
"G\NAC"4;
%"GND"
"1","(-5625,5075)","0","mstr_symbols","I46";
;
VOLTAGE"0"
CDS_LIB"mstr_symbols"
SIZE"1B"
ROOM"MIO_CHASSIS"
BODY_TYPE"PLUMBING"
HDL_POWER"GND";
"A\NAC"5;
%"RES"
"1","(-8100,6325)","0","mstr_discrete","I6";
;
PART_NUMBER"G21497-005"
VALUE"0.0"
TOLERANCE"5%"
MATERIAL"CHIP"
LOCATION"R1M10"
PACK_TYPE"0402"
WATTAGE"1/16W"
CDS_LIB"mstr_discrete"
CDS_SEC"1"
$SEC"1"
CDS_LOCATION"R1M10"
ROOM"MIO_CHASSIS";
"B"
$PN"2"13;
"A"
$PN"1"19;
%"TTL1G08"
"1","(-6550,6275)","0","mstr_ttl","I70";
;
CDS_SEC"1"
VALUE"NC7SZ08"
LOCATION"U1M1"
PART_NUMBER"D10321-001"
POWER_GROUP"VCC=P3V3;GND=GND;"
PACK_TYPE"SOTLF"
MATERIAL"IC"
CDS_LIB"mstr_ttl"
SEC_TYPE"SOTLF"
BOM_COST"MIO_CHASSIS"
SEC"1"
CDS_LOCATION"U1M1"
ROOM"MIO_CHASSIS";
"Y <SIZE-1..0>"
$PN"4"15;
"B <SIZE-1..0>"
$PN"2"14;
"A <SIZE-1..0>"
$PN"1"13;
%"LED"
"2","(-7200,8475)","0","mstr_discrete","I71";
;
CDS_SEC"1"
LOCATION"DS9F1"
PART_NUMBER"D14725-005"
MATERIAL"IC"
COLOR"RED"
PACK_TYPE"A1"
SEC_TYPE"A1"
CDS_LIB"mstr_discrete"
BOM_COST"SM_CONTROLLER"
SEC"1"
CDS_LOCATION"DS9F1"
ROOM"BMC";
"C"
$PN"2"20;
"A"
$PN"1"21;
%"RES"
"2","(-7200,8825)","0","mstr_discrete","I72";
;
CDS_SEC"1"
LOCATION"R9F28"
PART_NUMBER"G21796-271"
VALUE"221"
TOLERANCE"1.0%"
PACK_TYPE"0402"
MATERIAL"CHIP"
WATTAGE"1/16W"
SEC_TYPE"0402"
CDS_LIB"mstr_discrete"
BOM_COST"SM_CONTROLLER"
SEC"1"
CDS_LOCATION"R9F28"
ROOM"BMC";
"A"
$PN"1"8;
"B"
$PN"2"21;
%"GND"
"1","(-7200,7650)","0","mstr_symbols","I74";
;
VOLTAGE"0.0V"
SIZE"1B"
CDS_LIB"mstr_symbols"
BODY_TYPE"PLUMBING"
HDL_POWER"GND";
"A\NAC"6;
%"RES"
"2","(-8800,7850)","0","mstr_discrete","I76";
;
CDS_SEC"1"
PART_NUMBER"G21796-072"
WATTAGE"1/16W"
MATERIAL"CHIP"
PACK_TYPE"0402"
TOLERANCE"1%"
VALUE"4.75K"
LOCATION"R9F30"
ROOM"BMC"
CDS_LOCATION"R9F30"
SEC"1"
SEC_TYPE"0402"
CDS_LIB"mstr_discrete"
BOM_COST"SM_CONTROLLER";
"A"
$PN"1"7;
"B"
$PN"2"17;
%"P3V3_STBY"
"1","(-8800,8125)","0","mstr_symbols","I77";
;
HDL_POWER"P3V3_STBY"
BODY_TYPE"PLUMBING"
SIZE"1B"
CDS_LIB"mstr_symbols"
VOLTAGE"3.3V";
"G\NAC"7;
%"P3V3_STBY"
"1","(-7200,9125)","0","mstr_symbols","I78";
;
VOLTAGE"3.3V"
SIZE"1B"
CDS_LIB"mstr_symbols"
BODY_TYPE"PLUMBING"
HDL_POWER"P3V3_STBY";
"G\NAC"8;
%"FET_N_DUAL"
"5","(-7200,8050)","0","mstr_discrete","I79";
;
CDS_SEC"2"
LOCATION"Q9F1"
PART_NUMBER"E40049-001"
VALUE"NTJD4001N"
MATERIAL"FET"
PACK_TYPE"SMLF"
CDS_LIB"mstr_discrete"
BOM_COST"SM_CONTROLLER"
SEC_TYPE"SMLF"
SEC"2"
CDS_LOCATION"Q9F1"
ROOM"BMC";
"GATE <SIZE -1..0>"
$PN"5"12;
"SOURCE <SIZE-1..0>"
$PN"4"6;
"DRAIN <SIZE -1..0>"
$PN"3"20;
%"RES"
"2","(-6975,6550)","0","mstr_discrete","I8";
;
CDS_SEC"1"
LOCATION"R1M12"
VALUE"10.0K"
TOLERANCE"1%"
WATTAGE"1/16W"
MATERIAL"CHIP"
PACK_TYPE"0402"
PART_NUMBER"G21796-016"
SEC_TYPE"0402"
CDS_LIB"mstr_discrete"
SEC"1"
CDS_LOCATION"R1M12"
ROOM"MIO_CHASSIS";
"A"
$PN"1"1;
"B"
$PN"2"14;
%"FET_N_DUAL"
"5","(-8125,7675)","0","mstr_discrete","I80";
;
CDS_SEC"1"
MATERIAL"FET"
VALUE"NTJD4001N"
PART_NUMBER"E40049-001"
LOCATION"Q9F1"
ROOM"BMC"
CDS_LOCATION"Q9F1"
SEC"1"
BOM_COST"SM_CONTROLLER"
SEC_TYPE"SMLF"
CDS_LIB"mstr_discrete"
PACK_TYPE"SMLF";
"GATE <SIZE -1..0>"
$PN"2"17;
"SOURCE <SIZE-1..0>"
$PN"1"10;
"DRAIN <SIZE -1..0>"
$PN"6"12;
%"P3V3_STBY"
"1","(-8125,8500)","0","mstr_symbols","I81";
;
HDL_POWER"P3V3_STBY"
BODY_TYPE"PLUMBING"
CDS_LIB"mstr_symbols"
SIZE"1B"
VOLTAGE"3.3V";
"G\NAC"9;
%"RES"
"2","(-8125,8225)","0","mstr_discrete","I82";
;
CDS_SEC"1"
WATTAGE"1/16W"
MATERIAL"CHIP"
PACK_TYPE"0402"
TOLERANCE"1%"
VALUE"4.75K"
PART_NUMBER"G21796-072"
LOCATION"R9F52"
ROOM"BMC"
CDS_LOCATION"R9F52"
SEC"1"
BOM_COST"SM_CONTROLLER"
CDS_LIB"mstr_discrete"
SEC_TYPE"0402";
"A"
$PN"1"9;
"B"
$PN"2"12;
%"GND"
"1","(-8125,7325)","0","mstr_symbols","I83";
;
HDL_POWER"GND"
BODY_TYPE"PLUMBING"
SIZE"1B"
CDS_LIB"mstr_symbols"
VOLTAGE"0.0V";
"A\NAC"10;
%"P3V3"
"1","(-4675,6925)","0","mstr_symbols","I85";
;
VOLTAGE"3.3V"
CDS_LIB"mstr_symbols"
SIZE"1B"
BODY_TYPE"PLUMBING"
HDL_POWER"P3V3";
"G\NAC"11;
%"RES"
"2","(-7025,6550)","2","mstr_discrete","I9";
;
CDS_SEC"1"
PART_NUMBER"G21796-016"
TOLERANCE"1%"
MATERIAL"CHIP"
PACK_TYPE"0402"
LOCATION"R1M11"
VALUE"10.0K"
WATTAGE"1/16W"
SEC_TYPE"0402"
CDS_LIB"mstr_discrete"
SEC"1"
CDS_LOCATION"R1M11"
ROOM"MIO_CHASSIS";
"A"
$PN"1"1;
"B"
$PN"2"13;
END.
